FILE_TYPE = CONNECTIVITY;
{Allegro Design Entry HDL 17.2-2016 S081 (4005846) 1/11/2022}
"PAGE_NUMBER" = 41;
0"NC";
1"M_E_CPU1_SA_DQ<31:0>";
2"M_E_CPU1_SB_DQ<31:0>";
3"M_E_CPU1_SA_CB<7:0>";
4"M_E_CPU1_SB_CB<7:0>";
5"M_E_CPU1_SA_DQS_DP<9:0>";
6"M_E_CPU1_SB_DQS_DP<9:0>";
7"M_E_CPU1_SA_CA<6:0>";
8"M_E_CPU1_SB_CA<6:0>";
9"M_E_CPU1_SA_DQS_DN<9:0>";
10"M_E_CPU1_SB_DQS_DN<9:0>";
11"M_E_CPU1_ALERT_N";
12"TP_M_E_CPU1_SA_TEST39E";
13"M_E_CPU1_ALERT_R_N";
14"M_E_CPU1_CLK_DP<0>";
15"M_E_CPU1_CLK_DN<0>";
16"M_E_CPU1_SA_CS_N<0>";
17"M_E_CPU1_SA_RSP<0>";
18"M_E_CPU1_SA_CS_N<1>";
19"M_E_CPU1_SA_PAR";
20"M_E_CPU1_SB_CS_N<1>";
21"M_E_CPU1_SB_CS_N<0>";
22"M_E_CPU1_SB_RSP<0>";
23"M_E_CPU1_SB_PAR";
24"M_E_CPU1_RESET_N";
25"M_E_CPU1_SB_DQS_DP<9>";
26"M_E_CPU1_SB_CA<6>";
27"M_E_CPU1_SA_CA<6>";
28"M_E_CPU1_SB_CA<5>";
29"M_E_CPU1_SA_CA<5>";
30"M_E_CPU1_SB_CA<4>";
31"M_E_CPU1_SA_CA<4>";
32"M_E_CPU1_SB_CA<3>";
33"M_E_CPU1_SA_CA<3>";
34"M_E_CPU1_SB_CA<2>";
35"M_E_CPU1_SA_CA<2>";
36"M_E_CPU1_SB_CA<1>";
37"M_E_CPU1_SB_DQS_DN<9>";
38"M_E_CPU1_SA_CA<1>";
39"M_E_CPU1_SB_CA<0>";
40"M_E_CPU1_SB_DQS_DN<8>";
41"M_E_CPU1_SA_CA<0>";
42"M_E_CPU1_SB_DQS_DN<1>";
43"M_E_CPU1_SB_DQS_DN<0>";
44"M_E_CPU1_SB_DQS_DP<8>";
45"M_E_CPU1_SB_DQS_DP<7>";
46"M_E_CPU1_SB_DQS_DP<6>";
47"M_E_CPU1_SB_DQS_DP<5>";
48"M_E_CPU1_SB_DQS_DP<4>";
49"M_E_CPU1_SA_DQS_DP<9>";
50"M_E_CPU1_SB_DQS_DP<3>";
51"M_E_CPU1_SB_DQS_DN<7>";
52"M_E_CPU1_SB_DQS_DP<2>";
53"M_E_CPU1_SB_DQS_DN<6>";
54"M_E_CPU1_SB_DQS_DP<1>";
55"M_E_CPU1_SB_DQS_DN<5>";
56"M_E_CPU1_SB_DQS_DP<0>";
57"M_E_CPU1_SB_DQS_DN<4>";
58"M_E_CPU1_SA_DQS_DN<9>";
59"M_E_CPU1_SB_DQS_DN<3>";
60"M_E_CPU1_SB_DQS_DN<2>";
61"M_E_CPU1_SA_DQS_DP<3>";
62"M_E_CPU1_SA_DQS_DN<7>";
63"M_E_CPU1_SA_DQS_DP<2>";
64"M_E_CPU1_SA_DQS_DN<6>";
65"M_E_CPU1_SA_DQS_DP<1>";
66"M_E_CPU1_SA_DQS_DN<5>";
67"M_E_CPU1_SA_DQS_DP<0>";
68"M_E_CPU1_SA_DQS_DN<4>";
69"M_E_CPU1_SA_DQS_DN<3>";
70"M_E_CPU1_SA_DQS_DN<2>";
71"M_E_CPU1_SA_DQS_DN<1>";
72"M_E_CPU1_SA_DQS_DN<0>";
73"M_E_CPU1_SA_DQS_DP<8>";
74"M_E_CPU1_SA_DQS_DP<7>";
75"M_E_CPU1_SA_DQS_DP<6>";
76"M_E_CPU1_SA_DQS_DP<5>";
77"M_E_CPU1_SA_DQS_DP<4>";
78"M_E_CPU1_SA_DQS_DN<8>";
79"M_E_CPU1_SB_CB<5>";
80"M_E_CPU1_SB_CB<4>";
81"M_E_CPU1_SB_CB<3>";
82"M_E_CPU1_SB_CB<2>";
83"M_E_CPU1_SA_CB<7>";
84"M_E_CPU1_SB_CB<1>";
85"M_E_CPU1_SB_CB<0>";
86"M_E_CPU1_SB_CB<7>";
87"M_E_CPU1_SB_CB<6>";
88"M_E_CPU1_SB_DQ<25>";
89"M_E_CPU1_SB_DQ<24>";
90"M_E_CPU1_SB_DQ<23>";
91"M_E_CPU1_SB_DQ<22>";
92"M_E_CPU1_SB_DQ<21>";
93"M_E_CPU1_SA_CB<6>";
94"M_E_CPU1_SB_DQ<31>";
95"M_E_CPU1_SA_CB<5>";
96"M_E_CPU1_SB_DQ<30>";
97"M_E_CPU1_SA_CB<4>";
98"M_E_CPU1_SA_CB<3>";
99"M_E_CPU1_SA_CB<2>";
100"M_E_CPU1_SA_CB<1>";
101"M_E_CPU1_SA_CB<0>";
102"M_E_CPU1_SB_DQ<29>";
103"M_E_CPU1_SB_DQ<28>";
104"M_E_CPU1_SB_DQ<27>";
105"M_E_CPU1_SB_DQ<26>";
106"M_E_CPU1_SB_DQ<14>";
107"M_E_CPU1_SB_DQ<13>";
108"M_E_CPU1_SB_DQ<12>";
109"M_E_CPU1_SB_DQ<9>";
110"M_E_CPU1_SB_DQ<11>";
111"M_E_CPU1_SB_DQ<8>";
112"M_E_CPU1_SB_DQ<10>";
113"M_E_CPU1_SB_DQ<7>";
114"M_E_CPU1_SB_DQ<20>";
115"M_E_CPU1_SB_DQ<6>";
116"M_E_CPU1_SB_DQ<5>";
117"M_E_CPU1_SB_DQ<4>";
118"M_E_CPU1_SB_DQ<3>";
119"M_E_CPU1_SB_DQ<2>";
120"M_E_CPU1_SB_DQ<19>";
121"M_E_CPU1_SB_DQ<18>";
122"M_E_CPU1_SB_DQ<17>";
123"M_E_CPU1_SB_DQ<16>";
124"M_E_CPU1_SB_DQ<15>";
125"M_E_CPU1_SA_DQ<19>";
126"M_E_CPU1_SA_DQ<18>";
127"M_E_CPU1_SA_DQ<29>";
128"M_E_CPU1_SA_DQ<17>";
129"M_E_CPU1_SA_DQ<28>";
130"M_E_CPU1_SA_DQ<16>";
131"M_E_CPU1_SA_DQ<27>";
132"M_E_CPU1_SA_DQ<26>";
133"M_E_CPU1_SA_DQ<25>";
134"M_E_CPU1_SA_DQ<24>";
135"M_E_CPU1_SA_DQ<23>";
136"M_E_CPU1_SA_DQ<22>";
137"M_E_CPU1_SA_DQ<21>";
138"M_E_CPU1_SA_DQ<20>";
139"M_E_CPU1_SA_DQ<31>";
140"M_E_CPU1_SB_DQ<1>";
141"M_E_CPU1_SA_DQ<30>";
142"M_E_CPU1_SB_DQ<0>";
143"M_E_CPU1_SA_DQ<9>";
144"M_E_CPU1_SA_DQ<8>";
145"M_E_CPU1_SA_DQ<15>";
146"M_E_CPU1_SA_DQ<7>";
147"M_E_CPU1_SA_DQ<14>";
148"M_E_CPU1_SA_DQ<6>";
149"M_E_CPU1_SA_DQ<13>";
150"M_E_CPU1_SA_DQ<5>";
151"M_E_CPU1_SA_DQ<12>";
152"M_E_CPU1_SA_DQ<4>";
153"M_E_CPU1_SA_DQ<11>";
154"M_E_CPU1_SA_DQ<3>";
155"M_E_CPU1_SA_DQ<10>";
156"M_E_CPU1_SA_DQ<2>";
157"M_E_CPU1_SA_DQ<1>";
158"M_E_CPU1_SA_DQ<0>";
%"GENOA_SP5"
"5","(-4700,3600)","0","pure_quanta","I159";
;
LOCATION"U26"
$SEC"5"
CDS_SEC"5"
PART_TYPE"SMLF"
MATERIAL"IO"
VALUE"SOCKET6096_13568-001"
PART_NUMBER"DGA^6000030"
CDS_LIB"pure_quanta"
CDS_LMAN_SYM_OUTLINE"-650,2525,650,-2525"
NEEDS_NO_SIZE"TRUE";
"TEST39E"
$PN"BF69"12;
"ME1_CLK_L"
$PN"BG71"0;
"ME1_CLK_H"
$PN"BF70"0;
"ME0_CLK_L"
$PN"BD70"15;
"ME0_CLK_H"
$PN"BC71"14;
"MEB_DQS_H9"
$PN"BV70"25;
"MEB_PAR"
$PN"BL71"23;
"MEA_PAR"
$PN"BC69"19;
"MEA_DQS_H3"
$PN"AE71"61;
"MEA_DQS_L7"
$PN"Y69"62;
"MEB_CHECK5"
$PN"BU69"79;
"MEB_DATA14"
$PN"CN71"106;
"MEB_DATA25"
$PN"DA69"88;
"MEB_DQS_L1"
$PN"CL71"42;
"MEA_DATA19"
$PN"W69"125;
"MEA_DQS_H2"
$PN"W71"63;
"MEA_DQS_L6"
$PN"P69"64;
"MEB_CHECK4"
$PN"BT70"80;
"MEB_DATA13"
$PN"CN69"107;
"MEB_DATA24"
$PN"CY70"89;
"MEB_DQS_L0"
$PN"CE71"43;
"MEA_DATA18"
$PN"V70"126;
"MEA_DATA29"
$PN"AH69"127;
"MEA_DQS_H1"
$PN"N71"65;
"MEA_DQS_L5"
$PN"H69"66;
"MEB_CHECK3"
$PN"CB69"81;
"MEB_DATA12"
$PN"CM70"108;
"MEB_DATA23"
$PN"CY69"90;
"MEA_DATA17"
$PN"V69"128;
"MEA_DATA28"
$PN"AG71"129;
"MEA_DQS_H0"
$PN"G71"67;
"MEA_DQS_L4"
$PN"AM70"68;
"MEB_CHECK2"
$PN"CA71"82;
"MEB_DATA9"
$PN"CJ69"109;
"MEB_DATA11"
$PN"CK69"110;
"MEB_DATA22"
$PN"CW71"91;
"MEA0_RSP_L"
$PN"BN69"17;
"MEA1_RSP_L"
$PN"BP69"0;
"MEA_CHECK7"
$PN"AR69"83;
"MEA_DATA9"
$PN"M69"143;
"MEA_DATA16"
$PN"U71"130;
"MEA_DATA27"
$PN"AE69"131;
"MEA_DQS_L3"
$PN"AF70"69;
"MEB_CA6"
$PN"BK70"26;
"MEB_CHECK1"
$PN"CA69"84;
"MEB_DATA8"
$PN"CH70"111;
"MEB_DATA10"
$PN"CJ71"112;
"MEB_DATA21"
$PN"CW69"92;
"MEA_CA6"
$PN"BB69"27;
"MEA_CHECK6"
$PN"AP70"93;
"MEA_DATA8"
$PN"L71"144;
"MEA_DATA15"
$PN"U69"145;
"MEA_DATA26"
$PN"AD70"132;
"MEA_DQS_L2"
$PN"Y70"70;
"MEB_CA5"
$PN"BK69"28;
"MEB_CHECK0"
$PN"BY70"85;
"MEB_DATA7"
$PN"CH69"113;
"MEB_DATA20"
$PN"CV70"114;
"MEB_DATA31"
$PN"DF69"94;
"MEA_CA5"
$PN"BB70"29;
"MEA_CHECK5"
$PN"AP69"95;
"MEA_DATA7"
$PN"L69"146;
"MEA_DATA14"
$PN"T70"147;
"MEA_DATA25"
$PN"AD69"133;
"MEA_DQS_L1"
$PN"P70"71;
"MEB0_CS_L1"
$PN"BN71"20;
"MEB1_CS_L1"
$PN"BM70"0;
"MEB_CA4"
$PN"BJ69"30;
"MEB_DATA6"
$PN"CG71"115;
"MEB_DATA30"
$PN"DE71"96;
"MEB_DQS_H8"
$PN"DD69"44;
"MEA_CA4"
$PN"BA71"31;
"MEA_CHECK4"
$PN"AN71"97;
"MEA_DATA6"
$PN"K70"148;
"MEA_DATA13"
$PN"T69"149;
"MEA_DATA24"
$PN"AC71"134;
"MEA_DQS_L0"
$PN"H70"72;
"MEB0_CS_L0"
$PN"BM69"21;
"MEB1_CS_L0"
$PN"BL69"0;
"MEB_CA3"
$PN"BJ71"32;
"MEB_DATA5"
$PN"CG69"116;
"MEB_DQS_H7"
$PN"CV69"45;
"MEA_CA3"
$PN"BA69"33;
"MEA_CHECK3"
$PN"AL69"98;
"MEA_DATA5"
$PN"K69"150;
"MEA_DATA12"
$PN"R71"151;
"MEA_DATA23"
$PN"AC69"135;
"MEB_CA2"
$PN"BH70"34;
"MEB_DATA4"
$PN"CF70"117;
"MEB_DQS_H6"
$PN"CM69"46;
"MEA_CA2"
$PN"AY69"35;
"MEA_CHECK2"
$PN"AK70"99;
"MEA_DATA4"
$PN"J71"152;
"MEA_DATA11"
$PN"N69"153;
"MEA_DATA22"
$PN"AB70"136;
"MEB_CA1"
$PN"BH69"36;
"MEB_DATA3"
$PN"CD69"118;
"MEB_DQS_H5"
$PN"CF69"47;
"MEB_DQS_L9"
$PN"BW71"37;
"MEA_CA1"
$PN"AY70"38;
"MEA_CHECK1"
$PN"AK69"100;
"MEA_DATA3"
$PN"G69"154;
"MEA_DATA10"
$PN"M70"155;
"MEA_DATA21"
$PN"AB69"137;
"MEB_CA0"
$PN"BG69"39;
"MEB_DATA2"
$PN"CC71"119;
"MEB_DQS_H4"
$PN"BY69"48;
"MEB_DQS_L8"
$PN"DC69"40;
"MEA_CA0"
$PN"AW71"41;
"MEA_CHECK0"
$PN"AJ71"101;
"MEA_DATA2"
$PN"F70"156;
"MEA_DATA20"
$PN"AA71"138;
"MEA_DATA31"
$PN"AJ69"139;
"MEA_DQS_H9"
$PN"AN69"49;
"MEB_DATA1"
$PN"CC69"140;
"MEB_DQS_H3"
$PN"DB70"50;
"MEB_DQS_L7"
$PN"CU69"51;
"MEA0_CS_L1"
$PN"AW69"18;
"MEA1_CS_L1"
$PN"AV69"0;
"MEA_DATA1"
$PN"F69"157;
"MEA_DATA30"
$PN"AH70"141;
"MEA_DQS_H8"
$PN"AG69"73;
"MEB_DATA0"
$PN"CB70"142;
"MEB_DATA19"
$PN"CT69"120;
"MEB_DQS_H2"
$PN"CT70"52;
"MEB_DQS_L6"
$PN"CL69"53;
"MEA0_CS_L0"
$PN"AV70"16;
"MEA1_CS_L0"
$PN"AU71"0;
"MEA_DATA0"
$PN"E71"158;
"MEA_DQS_H7"
$PN"AA69"74;
"MEB_DATA18"
$PN"CR71"121;
"MEB_DATA29"
$PN"DE69"102;
"MEB_DQS_H1"
$PN"CK70"54;
"MEB_DQS_L5"
$PN"CE69"55;
"MEA_DQS_H6"
$PN"R69"75;
"MEB_DATA17"
$PN"CR69"122;
"MEB_DATA28"
$PN"DD70"103;
"MEB_DQS_H0"
$PN"CD70"56;
"MEB_DQS_L4"
$PN"BW69"57;
"MEA_DQS_H5"
$PN"J69"76;
"MEA_DQS_L9"
$PN"AM69"58;
"MEB0_RSP_L"
$PN"BP70"22;
"MEB1_RSP_L"
$PN"BR71"0;
"MEB_CHECK7"
$PN"BV69"86;
"MEB_DATA16"
$PN"CP70"123;
"MEB_DATA27"
$PN"DB69"104;
"MEB_DQS_L3"
$PN"DC71"59;
"MEA_DQS_H4"
$PN"AL71"77;
"MEA_DQS_L8"
$PN"AF69"78;
"MEB_CHECK6"
$PN"BU71"87;
"MEB_DATA15"
$PN"CP69"124;
"MEB_DATA26"
$PN"DA71"105;
"MEB_DQS_L2"
$PN"CU71"60;
"ME_RESET_L"
$PN"AU69"24;
"ME_ALERT_L"
$PN"AT69"13;
%"TAP"
"1","(-3425,5975)","0","mstr_standard","I162";
;
CDS_LIB"mstr_standard"
BODY_TYPE"PLUMBING"
HDL_TAP"TRUE";
"B \NAC \NWC"1;
"S \NAC"
BN"0"158;
%"TAP"
"1","(-3425,5925)","0","mstr_standard","I163";
;
CDS_LIB"mstr_standard"
BODY_TYPE"PLUMBING"
HDL_TAP"TRUE";
"B \NAC \NWC"1;
"S \NAC"
BN"1"157;
%"TAP"
"1","(-3425,5875)","0","mstr_standard","I164";
;
CDS_LIB"mstr_standard"
BODY_TYPE"PLUMBING"
HDL_TAP"TRUE";
"B \NAC \NWC"1;
"S \NAC"
BN"2"156;
%"TAP"
"1","(-3425,5825)","0","mstr_standard","I165";
;
CDS_LIB"mstr_standard"
BODY_TYPE"PLUMBING"
HDL_TAP"TRUE";
"B \NAC \NWC"1;
"S \NAC"
BN"3"154;
%"TAP"
"1","(-3425,5775)","0","mstr_standard","I166";
;
CDS_LIB"mstr_standard"
BODY_TYPE"PLUMBING"
HDL_TAP"TRUE";
"B \NAC \NWC"1;
"S \NAC"
BN"4"152;
%"TAP"
"1","(-3425,5725)","0","mstr_standard","I167";
;
CDS_LIB"mstr_standard"
BODY_TYPE"PLUMBING"
HDL_TAP"TRUE";
"B \NAC \NWC"1;
"S \NAC"
BN"5"150;
%"TAP"
"1","(-3425,5675)","0","mstr_standard","I168";
;
CDS_LIB"mstr_standard"
BODY_TYPE"PLUMBING"
HDL_TAP"TRUE";
"B \NAC \NWC"1;
"S \NAC"
BN"6"148;
%"TAP"
"1","(-3425,5625)","0","mstr_standard","I169";
;
CDS_LIB"mstr_standard"
BODY_TYPE"PLUMBING"
HDL_TAP"TRUE";
"B \NAC \NWC"1;
"S \NAC"
BN"7"146;
%"TAP"
"1","(-3425,5525)","0","mstr_standard","I170";
;
CDS_LIB"mstr_standard"
BODY_TYPE"PLUMBING"
HDL_TAP"TRUE";
"B \NAC \NWC"1;
"S \NAC"
BN"8"144;
%"TAP"
"1","(-3425,5475)","0","mstr_standard","I171";
;
CDS_LIB"mstr_standard"
BODY_TYPE"PLUMBING"
HDL_TAP"TRUE";
"B \NAC \NWC"1;
"S \NAC"
BN"9"143;
%"TAP"
"1","(-3425,5425)","0","mstr_standard","I172";
;
CDS_LIB"mstr_standard"
BODY_TYPE"PLUMBING"
HDL_TAP"TRUE";
"B \NAC \NWC"1;
"S \NAC"
BN"10"155;
%"TAP"
"1","(-3425,5375)","0","mstr_standard","I173";
;
CDS_LIB"mstr_standard"
BODY_TYPE"PLUMBING"
HDL_TAP"TRUE";
"B \NAC \NWC"1;
"S \NAC"
BN"11"153;
%"TAP"
"1","(-3425,5325)","0","mstr_standard","I174";
;
CDS_LIB"mstr_standard"
BODY_TYPE"PLUMBING"
HDL_TAP"TRUE";
"B \NAC \NWC"1;
"S \NAC"
BN"12"151;
%"TAP"
"1","(-3425,5275)","0","mstr_standard","I175";
;
CDS_LIB"mstr_standard"
BODY_TYPE"PLUMBING"
HDL_TAP"TRUE";
"B \NAC \NWC"1;
"S \NAC"
BN"13"149;
%"TAP"
"1","(-3425,5225)","0","mstr_standard","I176";
;
CDS_LIB"mstr_standard"
BODY_TYPE"PLUMBING"
HDL_TAP"TRUE";
"B \NAC \NWC"1;
"S \NAC"
BN"14"147;
%"TAP"
"1","(-3425,5175)","0","mstr_standard","I177";
;
CDS_LIB"mstr_standard"
BODY_TYPE"PLUMBING"
HDL_TAP"TRUE";
"B \NAC \NWC"1;
"S \NAC"
BN"15"145;
%"TAP"
"1","(-3425,5075)","0","mstr_standard","I178";
;
CDS_LIB"mstr_standard"
BODY_TYPE"PLUMBING"
HDL_TAP"TRUE";
"B \NAC \NWC"1;
"S \NAC"
BN"16"130;
%"TAP"
"1","(-3425,5025)","0","mstr_standard","I179";
;
CDS_LIB"mstr_standard"
BODY_TYPE"PLUMBING"
HDL_TAP"TRUE";
"B \NAC \NWC"1;
"S \NAC"
BN"17"128;
%"TAP"
"1","(-3425,4975)","0","mstr_standard","I180";
;
CDS_LIB"mstr_standard"
BODY_TYPE"PLUMBING"
HDL_TAP"TRUE";
"B \NAC \NWC"1;
"S \NAC"
BN"18"126;
%"TAP"
"1","(-3425,4875)","0","mstr_standard","I181";
;
CDS_LIB"mstr_standard"
BODY_TYPE"PLUMBING"
HDL_TAP"TRUE";
"B \NAC \NWC"1;
"S \NAC"
BN"20"138;
%"TAP"
"1","(-3425,4925)","0","mstr_standard","I182";
;
CDS_LIB"mstr_standard"
BODY_TYPE"PLUMBING"
HDL_TAP"TRUE";
"B \NAC \NWC"1;
"S \NAC"
BN"19"125;
%"TAP"
"1","(-3425,4825)","0","mstr_standard","I183";
;
CDS_LIB"mstr_standard"
BODY_TYPE"PLUMBING"
HDL_TAP"TRUE";
"B \NAC \NWC"1;
"S \NAC"
BN"21"137;
%"TAP"
"1","(-3425,4775)","0","mstr_standard","I184";
;
CDS_LIB"mstr_standard"
BODY_TYPE"PLUMBING"
HDL_TAP"TRUE";
"B \NAC \NWC"1;
"S \NAC"
BN"22"136;
%"TAP"
"1","(-3425,4725)","0","mstr_standard","I185";
;
CDS_LIB"mstr_standard"
BODY_TYPE"PLUMBING"
HDL_TAP"TRUE";
"B \NAC \NWC"1;
"S \NAC"
BN"23"135;
%"TAP"
"1","(-3425,4625)","0","mstr_standard","I186";
;
CDS_LIB"mstr_standard"
BODY_TYPE"PLUMBING"
HDL_TAP"TRUE";
"B \NAC \NWC"1;
"S \NAC"
BN"24"134;
%"TAP"
"1","(-3425,4575)","0","mstr_standard","I187";
;
CDS_LIB"mstr_standard"
BODY_TYPE"PLUMBING"
HDL_TAP"TRUE";
"B \NAC \NWC"1;
"S \NAC"
BN"25"133;
%"TAP"
"1","(-3425,4525)","0","mstr_standard","I188";
;
CDS_LIB"mstr_standard"
BODY_TYPE"PLUMBING"
HDL_TAP"TRUE";
"B \NAC \NWC"1;
"S \NAC"
BN"26"132;
%"TAP"
"1","(-3425,4425)","0","mstr_standard","I189";
;
CDS_LIB"mstr_standard"
BODY_TYPE"PLUMBING"
HDL_TAP"TRUE";
"B \NAC \NWC"1;
"S \NAC"
BN"28"129;
%"TAP"
"1","(-3425,4475)","0","mstr_standard","I190";
;
CDS_LIB"mstr_standard"
BODY_TYPE"PLUMBING"
HDL_TAP"TRUE";
"B \NAC \NWC"1;
"S \NAC"
BN"27"131;
%"TAP"
"1","(-3425,4375)","0","mstr_standard","I191";
;
CDS_LIB"mstr_standard"
BODY_TYPE"PLUMBING"
HDL_TAP"TRUE";
"B \NAC \NWC"1;
"S \NAC"
BN"29"127;
%"TAP"
"1","(-3425,4325)","0","mstr_standard","I192";
;
CDS_LIB"mstr_standard"
BODY_TYPE"PLUMBING"
HDL_TAP"TRUE";
"B \NAC \NWC"1;
"S \NAC"
BN"30"141;
%"TAP"
"1","(-3425,4275)","0","mstr_standard","I193";
;
CDS_LIB"mstr_standard"
BODY_TYPE"PLUMBING"
HDL_TAP"TRUE";
"B \NAC \NWC"1;
"S \NAC"
BN"31"139;
%"TAP"
"1","(-3425,4175)","0","mstr_standard","I194";
;
CDS_LIB"mstr_standard"
BODY_TYPE"PLUMBING"
HDL_TAP"TRUE";
"B \NAC \NWC"2;
"S \NAC"
BN"0"142;
%"TAP"
"1","(-3425,4125)","0","mstr_standard","I195";
;
CDS_LIB"mstr_standard"
BODY_TYPE"PLUMBING"
HDL_TAP"TRUE";
"B \NAC \NWC"2;
"S \NAC"
BN"1"140;
%"TAP"
"1","(-3425,4075)","0","mstr_standard","I197";
;
CDS_LIB"mstr_standard"
BODY_TYPE"PLUMBING"
HDL_TAP"TRUE";
"B \NAC \NWC"2;
"S \NAC"
BN"2"119;
%"TAP"
"1","(-3425,3975)","0","mstr_standard","I198";
;
CDS_LIB"mstr_standard"
BODY_TYPE"PLUMBING"
HDL_TAP"TRUE";
"B \NAC \NWC"2;
"S \NAC"
BN"4"117;
%"TAP"
"1","(-3425,4025)","0","mstr_standard","I199";
;
CDS_LIB"mstr_standard"
BODY_TYPE"PLUMBING"
HDL_TAP"TRUE";
"B \NAC \NWC"2;
"S \NAC"
BN"3"118;
%"TAP"
"1","(-3425,3925)","0","mstr_standard","I200";
;
CDS_LIB"mstr_standard"
BODY_TYPE"PLUMBING"
HDL_TAP"TRUE";
"B \NAC \NWC"2;
"S \NAC"
BN"5"116;
%"TAP"
"1","(-3425,3875)","0","mstr_standard","I201";
;
CDS_LIB"mstr_standard"
BODY_TYPE"PLUMBING"
HDL_TAP"TRUE";
"B \NAC \NWC"2;
"S \NAC"
BN"6"115;
%"TAP"
"1","(-3425,3825)","0","mstr_standard","I202";
;
CDS_LIB"mstr_standard"
BODY_TYPE"PLUMBING"
HDL_TAP"TRUE";
"B \NAC \NWC"2;
"S \NAC"
BN"7"113;
%"TAP"
"1","(-3425,3725)","0","mstr_standard","I203";
;
CDS_LIB"mstr_standard"
BODY_TYPE"PLUMBING"
HDL_TAP"TRUE";
"B \NAC \NWC"2;
"S \NAC"
BN"8"111;
%"TAP"
"1","(-3425,3675)","0","mstr_standard","I204";
;
CDS_LIB"mstr_standard"
BODY_TYPE"PLUMBING"
HDL_TAP"TRUE";
"B \NAC \NWC"2;
"S \NAC"
BN"9"109;
%"TAP"
"1","(-3425,3625)","0","mstr_standard","I205";
;
CDS_LIB"mstr_standard"
BODY_TYPE"PLUMBING"
HDL_TAP"TRUE";
"B \NAC \NWC"2;
"S \NAC"
BN"10"112;
%"TAP"
"1","(-3425,3575)","0","mstr_standard","I206";
;
CDS_LIB"mstr_standard"
BODY_TYPE"PLUMBING"
HDL_TAP"TRUE";
"B \NAC \NWC"2;
"S \NAC"
BN"11"110;
%"TAP"
"1","(-3425,3525)","0","mstr_standard","I207";
;
CDS_LIB"mstr_standard"
BODY_TYPE"PLUMBING"
HDL_TAP"TRUE";
"B \NAC \NWC"2;
"S \NAC"
BN"12"108;
%"TAP"
"1","(-3425,3475)","0","mstr_standard","I208";
;
CDS_LIB"mstr_standard"
BODY_TYPE"PLUMBING"
HDL_TAP"TRUE";
"B \NAC \NWC"2;
"S \NAC"
BN"13"107;
%"TAP"
"1","(-3425,3425)","0","mstr_standard","I209";
;
CDS_LIB"mstr_standard"
BODY_TYPE"PLUMBING"
HDL_TAP"TRUE";
"B \NAC \NWC"2;
"S \NAC"
BN"14"106;
%"TAP"
"1","(-3425,3375)","0","mstr_standard","I210";
;
CDS_LIB"mstr_standard"
BODY_TYPE"PLUMBING"
HDL_TAP"TRUE";
"B \NAC \NWC"2;
"S \NAC"
BN"15"124;
%"TAP"
"1","(-3425,3275)","0","mstr_standard","I211";
;
CDS_LIB"mstr_standard"
BODY_TYPE"PLUMBING"
HDL_TAP"TRUE";
"B \NAC \NWC"2;
"S \NAC"
BN"16"123;
%"TAP"
"1","(-3425,3225)","0","mstr_standard","I212";
;
CDS_LIB"mstr_standard"
BODY_TYPE"PLUMBING"
HDL_TAP"TRUE";
"B \NAC \NWC"2;
"S \NAC"
BN"17"122;
%"TAP"
"1","(-3425,3175)","0","mstr_standard","I213";
;
CDS_LIB"mstr_standard"
BODY_TYPE"PLUMBING"
HDL_TAP"TRUE";
"B \NAC \NWC"2;
"S \NAC"
BN"18"121;
%"TAP"
"1","(-3425,3075)","0","mstr_standard","I214";
;
CDS_LIB"mstr_standard"
BODY_TYPE"PLUMBING"
HDL_TAP"TRUE";
"B \NAC \NWC"2;
"S \NAC"
BN"20"114;
%"TAP"
"1","(-3425,3125)","0","mstr_standard","I215";
;
CDS_LIB"mstr_standard"
BODY_TYPE"PLUMBING"
HDL_TAP"TRUE";
"B \NAC \NWC"2;
"S \NAC"
BN"19"120;
%"TAP"
"1","(-3425,2975)","0","mstr_standard","I216";
;
CDS_LIB"mstr_standard"
BODY_TYPE"PLUMBING"
HDL_TAP"TRUE";
"B \NAC \NWC"2;
"S \NAC"
BN"22"91;
%"TAP"
"1","(-3425,3025)","0","mstr_standard","I217";
;
CDS_LIB"mstr_standard"
BODY_TYPE"PLUMBING"
HDL_TAP"TRUE";
"B \NAC \NWC"2;
"S \NAC"
BN"21"92;
%"TAP"
"1","(-3425,2825)","0","mstr_standard","I218";
;
CDS_LIB"mstr_standard"
BODY_TYPE"PLUMBING"
HDL_TAP"TRUE";
"B \NAC \NWC"2;
"S \NAC"
BN"24"89;
%"TAP"
"1","(-3425,2925)","0","mstr_standard","I219";
;
CDS_LIB"mstr_standard"
BODY_TYPE"PLUMBING"
HDL_TAP"TRUE";
"B \NAC \NWC"2;
"S \NAC"
BN"23"90;
%"TAP"
"1","(-3425,2775)","0","mstr_standard","I220";
;
CDS_LIB"mstr_standard"
BODY_TYPE"PLUMBING"
HDL_TAP"TRUE";
"B \NAC \NWC"2;
"S \NAC"
BN"25"88;
%"TAP"
"1","(-3425,2725)","0","mstr_standard","I221";
;
CDS_LIB"mstr_standard"
BODY_TYPE"PLUMBING"
HDL_TAP"TRUE";
"B \NAC \NWC"2;
"S \NAC"
BN"26"105;
%"TAP"
"1","(-3425,2625)","0","mstr_standard","I222";
;
CDS_LIB"mstr_standard"
BODY_TYPE"PLUMBING"
HDL_TAP"TRUE";
"B \NAC \NWC"2;
"S \NAC"
BN"28"103;
%"TAP"
"1","(-3425,2675)","0","mstr_standard","I223";
;
CDS_LIB"mstr_standard"
BODY_TYPE"PLUMBING"
HDL_TAP"TRUE";
"B \NAC \NWC"2;
"S \NAC"
BN"27"104;
%"TAP"
"1","(-3425,2575)","0","mstr_standard","I224";
;
CDS_LIB"mstr_standard"
BODY_TYPE"PLUMBING"
HDL_TAP"TRUE";
"B \NAC \NWC"2;
"S \NAC"
BN"29"102;
%"TAP"
"1","(-3425,2525)","0","mstr_standard","I225";
;
CDS_LIB"mstr_standard"
BODY_TYPE"PLUMBING"
HDL_TAP"TRUE";
"B \NAC \NWC"2;
"S \NAC"
BN"30"96;
%"TAP"
"1","(-3425,2475)","0","mstr_standard","I226";
;
CDS_LIB"mstr_standard"
BODY_TYPE"PLUMBING"
HDL_TAP"TRUE";
"B \NAC \NWC"2;
"S \NAC"
BN"31"94;
%"TAP"
"1","(-3425,2375)","0","mstr_standard","I227";
;
CDS_LIB"mstr_standard"
BODY_TYPE"PLUMBING"
HDL_TAP"TRUE";
"B \NAC \NWC"3;
"S \NAC"
BN"0"101;
%"TAP"
"1","(-3425,2325)","0","mstr_standard","I228";
;
CDS_LIB"mstr_standard"
BODY_TYPE"PLUMBING"
HDL_TAP"TRUE";
"B \NAC \NWC"3;
"S \NAC"
BN"1"100;
%"TAP"
"1","(-3425,2225)","0","mstr_standard","I229";
;
CDS_LIB"mstr_standard"
BODY_TYPE"PLUMBING"
HDL_TAP"TRUE";
"B \NAC \NWC"3;
"S \NAC"
BN"3"98;
%"TAP"
"1","(-3425,2275)","0","mstr_standard","I230";
;
CDS_LIB"mstr_standard"
BODY_TYPE"PLUMBING"
HDL_TAP"TRUE";
"B \NAC \NWC"3;
"S \NAC"
BN"2"99;
%"TAP"
"1","(-3425,2125)","0","mstr_standard","I231";
;
CDS_LIB"mstr_standard"
BODY_TYPE"PLUMBING"
HDL_TAP"TRUE";
"B \NAC \NWC"3;
"S \NAC"
BN"5"95;
%"TAP"
"1","(-3425,2175)","0","mstr_standard","I232";
;
CDS_LIB"mstr_standard"
BODY_TYPE"PLUMBING"
HDL_TAP"TRUE";
"B \NAC \NWC"3;
"S \NAC"
BN"4"97;
%"TAP"
"1","(-3425,2075)","0","mstr_standard","I233";
;
CDS_LIB"mstr_standard"
BODY_TYPE"PLUMBING"
HDL_TAP"TRUE";
"B \NAC \NWC"3;
"S \NAC"
BN"6"93;
%"TAP"
"1","(-3425,2025)","0","mstr_standard","I235";
;
CDS_LIB"mstr_standard"
BODY_TYPE"PLUMBING"
HDL_TAP"TRUE";
"B \NAC \NWC"3;
"S \NAC"
BN"7"83;
%"TAP"
"1","(-3425,1925)","0","mstr_standard","I236";
;
CDS_LIB"mstr_standard"
BODY_TYPE"PLUMBING"
HDL_TAP"TRUE";
"B \NAC \NWC"4;
"S \NAC"
BN"0"85;
%"TAP"
"1","(-3425,1875)","0","mstr_standard","I237";
;
CDS_LIB"mstr_standard"
BODY_TYPE"PLUMBING"
HDL_TAP"TRUE";
"B \NAC \NWC"4;
"S \NAC"
BN"1"84;
%"TAP"
"1","(-3425,1825)","0","mstr_standard","I238";
;
CDS_LIB"mstr_standard"
BODY_TYPE"PLUMBING"
HDL_TAP"TRUE";
"B \NAC \NWC"4;
"S \NAC"
BN"2"82;
%"TAP"
"1","(-3425,1775)","0","mstr_standard","I239";
;
CDS_LIB"mstr_standard"
BODY_TYPE"PLUMBING"
HDL_TAP"TRUE";
"B \NAC \NWC"4;
"S \NAC"
BN"3"81;
%"TAP"
"1","(-3425,1675)","0","mstr_standard","I240";
;
CDS_LIB"mstr_standard"
BODY_TYPE"PLUMBING"
HDL_TAP"TRUE";
"B \NAC \NWC"4;
"S \NAC"
BN"5"79;
%"TAP"
"1","(-3425,1725)","0","mstr_standard","I241";
;
CDS_LIB"mstr_standard"
BODY_TYPE"PLUMBING"
HDL_TAP"TRUE";
"B \NAC \NWC"4;
"S \NAC"
BN"4"80;
%"TAP"
"1","(-3425,1625)","0","mstr_standard","I242";
;
CDS_LIB"mstr_standard"
BODY_TYPE"PLUMBING"
HDL_TAP"TRUE";
"B \NAC \NWC"4;
"S \NAC"
BN"6"87;
%"TAP"
"1","(-3425,1575)","0","mstr_standard","I243";
;
CDS_LIB"mstr_standard"
BODY_TYPE"PLUMBING"
HDL_TAP"TRUE";
"B \NAC \NWC"4;
"S \NAC"
BN"7"86;
%"TAP"
"1","(-5850,5975)","2","mstr_standard","I244";
;
CDS_LIB"mstr_standard"
BODY_TYPE"PLUMBING"
HDL_TAP"TRUE";
"B \NAC \NWC"5;
"S \NAC"
BN"0"67;
%"TAP"
"1","(-5850,5875)","2","mstr_standard","I245";
;
CDS_LIB"mstr_standard"
BODY_TYPE"PLUMBING"
HDL_TAP"TRUE";
"B \NAC \NWC"5;
"S \NAC"
BN"1"65;
%"TAP"
"1","(-5850,5675)","2","mstr_standard","I246";
;
CDS_LIB"mstr_standard"
BODY_TYPE"PLUMBING"
HDL_TAP"TRUE";
"B \NAC \NWC"5;
"S \NAC"
BN"3"61;
%"TAP"
"1","(-5850,5775)","2","mstr_standard","I247";
;
CDS_LIB"mstr_standard"
BODY_TYPE"PLUMBING"
HDL_TAP"TRUE";
"B \NAC \NWC"5;
"S \NAC"
BN"2"63;
%"TAP"
"1","(-6050,5925)","2","mstr_standard","I248";
;
CDS_LIB"mstr_standard"
BODY_TYPE"PLUMBING"
HDL_TAP"TRUE";
"B \NAC \NWC"9;
"S \NAC"
BN"0"72;
%"TAP"
"1","(-6050,5825)","2","mstr_standard","I249";
;
CDS_LIB"mstr_standard"
BODY_TYPE"PLUMBING"
HDL_TAP"TRUE";
"B \NAC \NWC"9;
"S \NAC"
BN"1"71;
%"TAP"
"1","(-6050,5725)","2","mstr_standard","I250";
;
CDS_LIB"mstr_standard"
BODY_TYPE"PLUMBING"
HDL_TAP"TRUE";
"B \NAC \NWC"9;
"S \NAC"
BN"2"70;
%"TAP"
"1","(-5850,5475)","2","mstr_standard","I251";
;
CDS_LIB"mstr_standard"
BODY_TYPE"PLUMBING"
HDL_TAP"TRUE";
"B \NAC \NWC"5;
"S \NAC"
BN"5"76;
%"TAP"
"1","(-5850,5575)","2","mstr_standard","I252";
;
CDS_LIB"mstr_standard"
BODY_TYPE"PLUMBING"
HDL_TAP"TRUE";
"B \NAC \NWC"5;
"S \NAC"
BN"4"77;
%"TAP"
"1","(-5850,5375)","2","mstr_standard","I253";
;
CDS_LIB"mstr_standard"
BODY_TYPE"PLUMBING"
HDL_TAP"TRUE";
"B \NAC \NWC"5;
"S \NAC"
BN"6"75;
%"TAP"
"1","(-5850,5175)","2","mstr_standard","I254";
;
CDS_LIB"mstr_standard"
BODY_TYPE"PLUMBING"
HDL_TAP"TRUE";
"B \NAC \NWC"5;
"S \NAC"
BN"8"73;
%"TAP"
"1","(-5850,5275)","2","mstr_standard","I255";
;
CDS_LIB"mstr_standard"
BODY_TYPE"PLUMBING"
HDL_TAP"TRUE";
"B \NAC \NWC"5;
"S \NAC"
BN"7"74;
%"TAP"
"1","(-6050,5625)","2","mstr_standard","I256";
;
CDS_LIB"mstr_standard"
BODY_TYPE"PLUMBING"
HDL_TAP"TRUE";
"B \NAC \NWC"9;
"S \NAC"
BN"3"69;
%"TAP"
"1","(-6050,5525)","2","mstr_standard","I257";
;
CDS_LIB"mstr_standard"
BODY_TYPE"PLUMBING"
HDL_TAP"TRUE";
"B \NAC \NWC"9;
"S \NAC"
BN"4"68;
%"TAP"
"1","(-6050,5425)","2","mstr_standard","I258";
;
CDS_LIB"mstr_standard"
BODY_TYPE"PLUMBING"
HDL_TAP"TRUE";
"B \NAC \NWC"9;
"S \NAC"
BN"5"66;
%"TAP"
"1","(-6050,5325)","2","mstr_standard","I259";
;
CDS_LIB"mstr_standard"
BODY_TYPE"PLUMBING"
HDL_TAP"TRUE";
"B \NAC \NWC"9;
"S \NAC"
BN"6"64;
%"TAP"
"1","(-6050,5125)","2","mstr_standard","I260";
;
CDS_LIB"mstr_standard"
BODY_TYPE"PLUMBING"
HDL_TAP"TRUE";
"B \NAC \NWC"9;
"S \NAC"
BN"8"78;
%"TAP"
"1","(-6050,5225)","2","mstr_standard","I261";
;
CDS_LIB"mstr_standard"
BODY_TYPE"PLUMBING"
HDL_TAP"TRUE";
"B \NAC \NWC"9;
"S \NAC"
BN"7"62;
%"TAP"
"1","(-5850,4925)","2","mstr_standard","I262";
;
CDS_LIB"mstr_standard"
BODY_TYPE"PLUMBING"
HDL_TAP"TRUE";
"B \NAC \NWC"6;
"S \NAC"
BN"0"56;
%"TAP"
"1","(-5850,5075)","2","mstr_standard","I263";
;
CDS_LIB"mstr_standard"
BODY_TYPE"PLUMBING"
HDL_TAP"TRUE";
"B \NAC \NWC"5;
"S \NAC"
BN"9"49;
%"TAP"
"1","(-5850,4825)","2","mstr_standard","I264";
;
CDS_LIB"mstr_standard"
BODY_TYPE"PLUMBING"
HDL_TAP"TRUE";
"B \NAC \NWC"6;
"S \NAC"
BN"1"54;
%"TAP"
"1","(-5850,4725)","2","mstr_standard","I265";
;
CDS_LIB"mstr_standard"
BODY_TYPE"PLUMBING"
HDL_TAP"TRUE";
"B \NAC \NWC"6;
"S \NAC"
BN"2"52;
%"TAP"
"1","(-5850,4625)","2","mstr_standard","I266";
;
CDS_LIB"mstr_standard"
BODY_TYPE"PLUMBING"
HDL_TAP"TRUE";
"B \NAC \NWC"6;
"S \NAC"
BN"3"50;
%"TAP"
"1","(-6050,5025)","2","mstr_standard","I267";
;
CDS_LIB"mstr_standard"
BODY_TYPE"PLUMBING"
HDL_TAP"TRUE";
"B \NAC \NWC"9;
"S \NAC"
BN"9"58;
%"TAP"
"1","(-6050,4875)","2","mstr_standard","I268";
;
CDS_LIB"mstr_standard"
BODY_TYPE"PLUMBING"
HDL_TAP"TRUE";
"B \NAC \NWC"10;
"S \NAC"
BN"0"43;
%"TAP"
"1","(-6050,4775)","2","mstr_standard","I269";
;
CDS_LIB"mstr_standard"
BODY_TYPE"PLUMBING"
HDL_TAP"TRUE";
"B \NAC \NWC"10;
"S \NAC"
BN"1"42;
%"TAP"
"1","(-6050,4675)","2","mstr_standard","I270";
;
CDS_LIB"mstr_standard"
BODY_TYPE"PLUMBING"
HDL_TAP"TRUE";
"B \NAC \NWC"10;
"S \NAC"
BN"2"60;
%"TAP"
"1","(-5850,4425)","2","mstr_standard","I271";
;
CDS_LIB"mstr_standard"
BODY_TYPE"PLUMBING"
HDL_TAP"TRUE";
"B \NAC \NWC"6;
"S \NAC"
BN"5"47;
%"TAP"
"1","(-5850,4525)","2","mstr_standard","I272";
;
CDS_LIB"mstr_standard"
BODY_TYPE"PLUMBING"
HDL_TAP"TRUE";
"B \NAC \NWC"6;
"S \NAC"
BN"4"48;
%"TAP"
"1","(-5850,4325)","2","mstr_standard","I273";
;
CDS_LIB"mstr_standard"
BODY_TYPE"PLUMBING"
HDL_TAP"TRUE";
"B \NAC \NWC"6;
"S \NAC"
BN"6"46;
%"TAP"
"1","(-5850,4125)","2","mstr_standard","I274";
;
CDS_LIB"mstr_standard"
BODY_TYPE"PLUMBING"
HDL_TAP"TRUE";
"B \NAC \NWC"6;
"S \NAC"
BN"8"44;
%"TAP"
"1","(-5850,4225)","2","mstr_standard","I275";
;
CDS_LIB"mstr_standard"
BODY_TYPE"PLUMBING"
HDL_TAP"TRUE";
"B \NAC \NWC"6;
"S \NAC"
BN"7"45;
%"TAP"
"1","(-6050,4575)","2","mstr_standard","I276";
;
CDS_LIB"mstr_standard"
BODY_TYPE"PLUMBING"
HDL_TAP"TRUE";
"B \NAC \NWC"10;
"S \NAC"
BN"3"59;
%"TAP"
"1","(-6050,4475)","2","mstr_standard","I277";
;
CDS_LIB"mstr_standard"
BODY_TYPE"PLUMBING"
HDL_TAP"TRUE";
"B \NAC \NWC"10;
"S \NAC"
BN"4"57;
%"TAP"
"1","(-6050,4375)","2","mstr_standard","I278";
;
CDS_LIB"mstr_standard"
BODY_TYPE"PLUMBING"
HDL_TAP"TRUE";
"B \NAC \NWC"10;
"S \NAC"
BN"5"55;
%"TAP"
"1","(-6050,4275)","2","mstr_standard","I279";
;
CDS_LIB"mstr_standard"
BODY_TYPE"PLUMBING"
HDL_TAP"TRUE";
"B \NAC \NWC"10;
"S \NAC"
BN"6"53;
%"TAP"
"1","(-6050,4175)","2","mstr_standard","I280";
;
CDS_LIB"mstr_standard"
BODY_TYPE"PLUMBING"
HDL_TAP"TRUE";
"B \NAC \NWC"10;
"S \NAC"
BN"7"51;
%"TAP"
"1","(-5850,4025)","2","mstr_standard","I285";
;
CDS_LIB"mstr_standard"
BODY_TYPE"PLUMBING"
HDL_TAP"TRUE";
"B \NAC \NWC"6;
"S \NAC"
BN"9"25;
%"TAP"
"1","(-6050,4075)","2","mstr_standard","I286";
;
CDS_LIB"mstr_standard"
BODY_TYPE"PLUMBING"
HDL_TAP"TRUE";
"B \NAC \NWC"10;
"S \NAC"
BN"8"40;
%"TAP"
"1","(-6050,3975)","2","mstr_standard","I287";
;
CDS_LIB"mstr_standard"
BODY_TYPE"PLUMBING"
HDL_TAP"TRUE";
"B \NAC \NWC"10;
"S \NAC"
BN"9"37;
%"TAP"
"1","(-6050,3825)","2","mstr_standard","I288";
;
CDS_LIB"mstr_standard"
BODY_TYPE"PLUMBING"
HDL_TAP"TRUE";
"B \NAC \NWC"7;
"S \NAC"
BN"0"41;
%"TAP"
"1","(-6050,3775)","2","mstr_standard","I289";
;
CDS_LIB"mstr_standard"
BODY_TYPE"PLUMBING"
HDL_TAP"TRUE";
"B \NAC \NWC"7;
"S \NAC"
BN"1"38;
%"TAP"
"1","(-6050,3725)","2","mstr_standard","I290";
;
CDS_LIB"mstr_standard"
BODY_TYPE"PLUMBING"
HDL_TAP"TRUE";
"B \NAC \NWC"7;
"S \NAC"
BN"2"35;
%"TAP"
"1","(-6050,3675)","2","mstr_standard","I291";
;
CDS_LIB"mstr_standard"
BODY_TYPE"PLUMBING"
HDL_TAP"TRUE";
"B \NAC \NWC"7;
"S \NAC"
BN"3"33;
%"TAP"
"1","(-6050,3625)","2","mstr_standard","I292";
;
CDS_LIB"mstr_standard"
BODY_TYPE"PLUMBING"
HDL_TAP"TRUE";
"B \NAC \NWC"7;
"S \NAC"
BN"4"31;
%"TAP"
"1","(-6050,3575)","2","mstr_standard","I293";
;
CDS_LIB"mstr_standard"
BODY_TYPE"PLUMBING"
HDL_TAP"TRUE";
"B \NAC \NWC"7;
"S \NAC"
BN"5"29;
%"TAP"
"1","(-6050,3525)","2","mstr_standard","I294";
;
CDS_LIB"mstr_standard"
BODY_TYPE"PLUMBING"
HDL_TAP"TRUE";
"B \NAC \NWC"7;
"S \NAC"
BN"6"27;
%"TAP"
"1","(-6050,3425)","2","mstr_standard","I295";
;
CDS_LIB"mstr_standard"
BODY_TYPE"PLUMBING"
HDL_TAP"TRUE";
"B \NAC \NWC"8;
"S \NAC"
BN"0"39;
%"TAP"
"1","(-6050,3375)","2","mstr_standard","I296";
;
CDS_LIB"mstr_standard"
BODY_TYPE"PLUMBING"
HDL_TAP"TRUE";
"B \NAC \NWC"8;
"S \NAC"
BN"1"36;
%"TAP"
"1","(-6050,3325)","2","mstr_standard","I297";
;
CDS_LIB"mstr_standard"
BODY_TYPE"PLUMBING"
HDL_TAP"TRUE";
"B \NAC \NWC"8;
"S \NAC"
BN"2"34;
%"TAP"
"1","(-6050,3275)","2","mstr_standard","I298";
;
CDS_LIB"mstr_standard"
BODY_TYPE"PLUMBING"
HDL_TAP"TRUE";
"B \NAC \NWC"8;
"S \NAC"
BN"3"32;
%"TAP"
"1","(-6050,3225)","2","mstr_standard","I299";
;
CDS_LIB"mstr_standard"
BODY_TYPE"PLUMBING"
HDL_TAP"TRUE";
"B \NAC \NWC"8;
"S \NAC"
BN"4"30;
%"TAP"
"1","(-6050,3125)","2","mstr_standard","I300";
;
CDS_LIB"mstr_standard"
BODY_TYPE"PLUMBING"
HDL_TAP"TRUE";
"B \NAC \NWC"8;
"S \NAC"
BN"6"26;
%"TAP"
"1","(-6050,3175)","2","mstr_standard","I301";
;
CDS_LIB"mstr_standard"
BODY_TYPE"PLUMBING"
HDL_TAP"TRUE";
"B \NAC \NWC"8;
"S \NAC"
BN"5"28;
%"Q_RES"
"1","(-6725,2125)","0","pure_quanta","I314";
;
LOCATION"R504"
$SEC"1"
CDS_SEC"1"
TOLERANCE"1%"
VALUE"15   "
PART_NUMBER"CS01502FB11"
PACK_TYPE"0402LF"
CDS_LIB"pure_quanta"
WATTAGE"1/16W"
MATERIAL"CHIP";
"B"
$PN"2"13;
"A"
$PN"1"11;
END.
